(kicad_pcb
	(version 20260206)
	(generator "pcbnew")
	(generator_version "10.0")
	(general
		(thickness 1.6)
		(legacy_teardrops no)
	)
	(paper "A4")
	(title_block
		(title "Wiwynn_Tioga_Pass_MB.brd")
		(comment 1 "Tioga Pass / footprints 4183-4190 of 4770")
	)
	(layers
		(0 "F.Cu" signal "TOP")
		(4 "In1.Cu" signal "L2GND")
		(6 "In2.Cu" signal "L3")
		(8 "In3.Cu" signal "L4GND")
		(10 "In4.Cu" signal "L5")
		(12 "In5.Cu" signal "L6GND")
		(14 "In6.Cu" signal "L7VCC")
		(16 "In7.Cu" signal "L8VCC")
		(18 "In8.Cu" signal "L9GND")
		(20 "In9.Cu" signal "L10")
		(22 "In10.Cu" signal "L11GND")
		(24 "In11.Cu" signal "L12")
		(26 "In12.Cu" signal "L13GND")
		(2 "B.Cu" signal "BOTTOM")
		(9 "F.Adhes" user "F.Adhesive")
		(11 "B.Adhes" user "B.Adhesive")
		(13 "F.Paste" user "Package Geometry/Pastemask Top")
		(15 "B.Paste" user "Package Geometry/Pastemask Bottom")
		(5 "F.SilkS" user "Ref Des/Silkscreen Top")
		(7 "B.SilkS" user "Ref Des/Silkscreen Bottom")
		(1 "F.Mask" user "Board Geometry/Soldermask Top")
		(3 "B.Mask" user "Board Geometry/Soldermask Bottom")
		(17 "Dwgs.User" user "User.Drawings")
		(19 "Cmts.User" user "User.Comments")
		(21 "Eco1.User" user "User.Eco1")
		(23 "Eco2.User" user "User.Eco2")
		(25 "Edge.Cuts" user "Board Geometry/Outline")
		(27 "Margin" user)
		(31 "F.CrtYd" user "Package Geometry/Place Bound Top")
		(29 "B.CrtYd" user "Package Geometry/Place Bound Bottom")
		(35 "F.Fab" user "Ref Des/Assembly Top")
		(33 "B.Fab" user "Ref Des/Assembly Bottom")
	)
	(footprint ""
		(layer "B.Cu")
		(at 103.073454 -79.60614 180)
		(property "Reference" "C8P10"
			(at 0 0 0)
			(layer "B.SilkS")
			(hide yes)
			(effects
				(font
					(size 1.27 1.27)
				)
				(justify mirror)
			)
		)
		(property "Value" ""
			(at 0 0 0)
			(layer "B.Fab")
			(effects
				(font
					(size 1.27 1.27)
				)
				(justify mirror)
			)
		)
		(duplicate_pad_numbers_are_jumpers no)
		(fp_poly
			(pts
				(xy 0.7239 -0.2159) (xy -0.7239 -0.2159) (xy -0.7239 1.9939) (xy 0.7239 1.9939)
			)
			(stroke
				(width 0)
				(type default)
			)
			(fill no)
			(layer "B.CrtYd")
		)
		(fp_line
			(start 0.7239 1.9939)
			(end -0.7239 1.9939)
			(stroke
				(width 0.1)
				(type default)
			)
			(layer "B.Fab")
		)
		(fp_line
			(start 0.7239 -0.2159)
			(end 0.7239 1.9939)
			(stroke
				(width 0.1)
				(type default)
			)
			(layer "B.Fab")
		)
		(fp_line
			(start -0.7239 1.9939)
			(end -0.7239 -0.2159)
			(stroke
				(width 0.1)
				(type default)
			)
			(layer "B.Fab")
		)
		(fp_line
			(start -0.7239 -0.2159)
			(end 0.7239 -0.2159)
			(stroke
				(width 0.1)
				(type default)
			)
			(layer "B.Fab")
		)
		(pad "1" smd rect
			(at 0 0)
			(size 1.27 1.016)
			(layers "B.Cu" "B.Mask" "B.Paste")
			(net "PVCCIN_CPU1")
		)
		(pad "2" smd rect
			(at 0 1.778)
			(size 1.27 1.016)
			(layers "B.Cu" "B.Mask" "B.Paste")
			(net "GND")
		)
		(zone
			(layer "B.Cu")
			(hatch none 0.5)
			(connect_pads
				(clearance 0)
			)
			(min_thickness 0.25)
			(keepout
				(tracks not_allowed)
				(vias allowed)
				(pads allowed)
				(copperpour not_allowed)
				(footprints allowed)
			)
			(placement
				(enabled no)
				(sheetname "")
			)
			(fill
				(thermal_gap 0.5)
				(thermal_bridge_width 0.5)
				(island_removal_mode 0)
			)
			(polygon
				(pts
					(xy 102.438454 -80.11414) (xy 103.708454 -80.11414) (xy 103.708454 -80.87614) (xy 102.438454 -80.87614)
				)
			)
		)
	)
	(footprint ""
		(layer "B.Cu")
		(at 323.8627 -32.93618 -90)
		(property "Reference" "R4T3"
			(at 0 0 90)
			(layer "B.SilkS")
			(hide yes)
			(effects
				(font
					(size 1.27 1.27)
				)
				(justify mirror)
			)
		)
		(property "Value" ""
			(at 0 0 90)
			(layer "B.Fab")
			(effects
				(font
					(size 1.27 1.27)
				)
				(justify mirror)
			)
		)
		(duplicate_pad_numbers_are_jumpers no)
		(fp_poly
			(pts
				(xy 0.2794 -0.1016) (xy -0.2794 -0.1016) (xy -0.2794 0.9906) (xy 0.2794 0.9906)
			)
			(stroke
				(width 0)
				(type default)
			)
			(fill no)
			(layer "B.CrtYd")
		)
		(fp_line
			(start -0.2794 0.9906)
			(end -0.2794 -0.1016)
			(stroke
				(width 0.1)
				(type default)
			)
			(layer "B.Fab")
		)
		(fp_line
			(start 0.2794 0.9906)
			(end -0.2794 0.9906)
			(stroke
				(width 0.1)
				(type default)
			)
			(layer "B.Fab")
		)
		(fp_line
			(start -0.2794 -0.1016)
			(end 0.2794 -0.1016)
			(stroke
				(width 0.1)
				(type default)
			)
			(layer "B.Fab")
		)
		(fp_line
			(start 0.2794 -0.1016)
			(end 0.2794 0.9906)
			(stroke
				(width 0.1)
				(type default)
			)
			(layer "B.Fab")
		)
		(pad "1" smd rect
			(at 0 0 90)
			(size 0.508 0.508)
			(layers "B.Cu" "B.Mask" "B.Paste")
			(net "SMB_DDR_ABC_SCL_G_R")
		)
		(pad "2" smd rect
			(at 0 0.889 90)
			(size 0.508 0.508)
			(layers "B.Cu" "B.Mask" "B.Paste")
			(net "SMB_DDR_ABC_SCL_G")
		)
		(zone
			(layer "B.Cu")
			(hatch none 0.5)
			(connect_pads
				(clearance 0)
			)
			(min_thickness 0.25)
			(keepout
				(tracks not_allowed)
				(vias allowed)
				(pads allowed)
				(copperpour not_allowed)
				(footprints allowed)
			)
			(placement
				(enabled no)
				(sheetname "")
			)
			(fill
				(thermal_gap 0.5)
				(thermal_bridge_width 0.5)
				(island_removal_mode 0)
			)
			(polygon
				(pts
					(xy 323.2277 -32.68218) (xy 323.2277 -33.19018) (xy 323.6087 -33.19018) (xy 323.6087 -32.68218)
				)
			)
		)
		(zone
			(layer "B.Cu")
			(hatch none 0.5)
			(connect_pads
				(clearance 0)
			)
			(min_thickness 0.25)
			(keepout
				(tracks allowed)
				(vias not_allowed)
				(pads allowed)
				(copperpour not_allowed)
				(footprints allowed)
			)
			(placement
				(enabled no)
				(sheetname "")
			)
			(fill
				(thermal_gap 0.5)
				(thermal_bridge_width 0.5)
				(island_removal_mode 0)
			)
			(polygon
				(pts
					(xy 323.6087 -32.68218) (xy 323.6087 -33.19018) (xy 323.2277 -33.19018) (xy 323.2277 -32.68218)
				)
			)
		)
	)
	(footprint ""
		(layer "B.Cu")
		(at 406.908 -23.0505)
		(property "Reference" "R25W111"
			(at 0.8382 -0.67818 0)
			(unlocked yes)
			(layer "B.SilkS")
			(effects
				(font
					(size 0.4064 0.254)
					(thickness 0.1524)
				)
				(justify left mirror)
			)
		)
		(property "Value" ""
			(at 0 0 0)
			(layer "B.Fab")
			(effects
				(font
					(size 1.27 1.27)
				)
				(justify mirror)
			)
		)
		(duplicate_pad_numbers_are_jumpers no)
		(fp_poly
			(pts
				(xy 0.2794 -0.1016) (xy -0.2794 -0.1016) (xy -0.2794 0.9906) (xy 0.2794 0.9906)
			)
			(stroke
				(width 0)
				(type default)
			)
			(fill no)
			(layer "B.CrtYd")
		)
		(fp_line
			(start -0.2794 -0.1016)
			(end 0.2794 -0.1016)
			(stroke
				(width 0.1)
				(type default)
			)
			(layer "B.Fab")
		)
		(fp_line
			(start -0.2794 0.9906)
			(end -0.2794 -0.1016)
			(stroke
				(width 0.1)
				(type default)
			)
			(layer "B.Fab")
		)
		(fp_line
			(start 0.2794 -0.1016)
			(end 0.2794 0.9906)
			(stroke
				(width 0.1)
				(type default)
			)
			(layer "B.Fab")
		)
		(fp_line
			(start 0.2794 0.9906)
			(end -0.2794 0.9906)
			(stroke
				(width 0.1)
				(type default)
			)
			(layer "B.Fab")
		)
		(pad "1" smd rect
			(at 0 0 180)
			(size 0.508 0.508)
			(layers "B.Cu" "B.Mask" "B.Paste")
			(net "P3V3_STBY")
		)
		(pad "2" smd rect
			(at 0 0.889 180)
			(size 0.508 0.508)
			(layers "B.Cu" "B.Mask" "B.Paste")
			(net "RMII_BMC_PCH_SPRNGVLLE_TXEN")
		)
		(zone
			(layer "B.Cu")
			(hatch none 0.5)
			(connect_pads
				(clearance 0)
			)
			(min_thickness 0.25)
			(keepout
				(tracks allowed)
				(vias not_allowed)
				(pads allowed)
				(copperpour not_allowed)
				(footprints allowed)
			)
			(placement
				(enabled no)
				(sheetname "")
			)
			(fill
				(thermal_gap 0.5)
				(thermal_bridge_width 0.5)
				(island_removal_mode 0)
			)
			(polygon
				(pts
					(xy 407.162 -22.7965) (xy 406.654 -22.7965) (xy 406.654 -22.4155) (xy 407.162 -22.4155)
				)
			)
		)
		(zone
			(layer "B.Cu")
			(hatch none 0.5)
			(connect_pads
				(clearance 0)
			)
			(min_thickness 0.25)
			(keepout
				(tracks not_allowed)
				(vias allowed)
				(pads allowed)
				(copperpour not_allowed)
				(footprints allowed)
			)
			(placement
				(enabled no)
				(sheetname "")
			)
			(fill
				(thermal_gap 0.5)
				(thermal_bridge_width 0.5)
				(island_removal_mode 0)
			)
			(polygon
				(pts
					(xy 407.162 -22.4155) (xy 406.654 -22.4155) (xy 406.654 -22.7965) (xy 407.162 -22.7965)
				)
			)
		)
	)
	(footprint ""
		(layer "B.Cu")
		(at 482.4857 -148.93671)
		(property "Reference" "R6W49"
			(at 0.8382 -0.67818 0)
			(unlocked yes)
			(layer "B.SilkS")
			(effects
				(font
					(size 0.4064 0.254)
					(thickness 0.1524)
				)
				(justify left mirror)
			)
		)
		(property "Value" ""
			(at 0 0 0)
			(layer "B.Fab")
			(effects
				(font
					(size 1.27 1.27)
				)
				(justify mirror)
			)
		)
		(duplicate_pad_numbers_are_jumpers no)
		(fp_poly
			(pts
				(xy 0.2794 -0.1016) (xy -0.2794 -0.1016) (xy -0.2794 0.9906) (xy 0.2794 0.9906)
			)
			(stroke
				(width 0)
				(type default)
			)
			(fill no)
			(layer "B.CrtYd")
		)
		(fp_line
			(start -0.2794 -0.1016)
			(end 0.2794 -0.1016)
			(stroke
				(width 0.1)
				(type default)
			)
			(layer "B.Fab")
		)
		(fp_line
			(start -0.2794 0.9906)
			(end -0.2794 -0.1016)
			(stroke
				(width 0.1)
				(type default)
			)
			(layer "B.Fab")
		)
		(fp_line
			(start 0.2794 -0.1016)
			(end 0.2794 0.9906)
			(stroke
				(width 0.1)
				(type default)
			)
			(layer "B.Fab")
		)
		(fp_line
			(start 0.2794 0.9906)
			(end -0.2794 0.9906)
			(stroke
				(width 0.1)
				(type default)
			)
			(layer "B.Fab")
		)
		(pad "1" smd rect
			(at 0 0 180)
			(size 0.508 0.508)
			(layers "B.Cu" "B.Mask" "B.Paste")
			(net "FM_UART_SWITCH_N")
		)
		(pad "2" smd rect
			(at 0 0.889 180)
			(size 0.508 0.508)
			(layers "B.Cu" "B.Mask" "B.Paste")
			(net "FM_UART_SEL_N")
		)
		(zone
			(layer "B.Cu")
			(hatch none 0.5)
			(connect_pads
				(clearance 0)
			)
			(min_thickness 0.25)
			(keepout
				(tracks allowed)
				(vias not_allowed)
				(pads allowed)
				(copperpour not_allowed)
				(footprints allowed)
			)
			(placement
				(enabled no)
				(sheetname "")
			)
			(fill
				(thermal_gap 0.5)
				(thermal_bridge_width 0.5)
				(island_removal_mode 0)
			)
			(polygon
				(pts
					(xy 482.7397 -148.68271) (xy 482.2317 -148.68271) (xy 482.2317 -148.30171) (xy 482.7397 -148.30171)
				)
			)
		)
		(zone
			(layer "B.Cu")
			(hatch none 0.5)
			(connect_pads
				(clearance 0)
			)
			(min_thickness 0.25)
			(keepout
				(tracks not_allowed)
				(vias allowed)
				(pads allowed)
				(copperpour not_allowed)
				(footprints allowed)
			)
			(placement
				(enabled no)
				(sheetname "")
			)
			(fill
				(thermal_gap 0.5)
				(thermal_bridge_width 0.5)
				(island_removal_mode 0)
			)
			(polygon
				(pts
					(xy 482.7397 -148.30171) (xy 482.2317 -148.30171) (xy 482.2317 -148.68271) (xy 482.7397 -148.68271)
				)
			)
		)
	)
	(footprint ""
		(layer "B.Cu")
		(at 399.891758 -116.317014 180)
		(property "Reference" "R7W20"
			(at 0.8382 -0.67818 180)
			(unlocked yes)
			(layer "B.SilkS")
			(effects
				(font
					(size 0.4064 0.254)
					(thickness 0.1524)
				)
				(justify left mirror)
			)
		)
		(property "Value" ""
			(at 0 0 0)
			(layer "B.Fab")
			(effects
				(font
					(size 1.27 1.27)
				)
				(justify mirror)
			)
		)
		(duplicate_pad_numbers_are_jumpers no)
		(fp_poly
			(pts
				(xy 0.2794 -0.1016) (xy -0.2794 -0.1016) (xy -0.2794 0.9906) (xy 0.2794 0.9906)
			)
			(stroke
				(width 0)
				(type default)
			)
			(fill no)
			(layer "B.CrtYd")
		)
		(fp_line
			(start 0.2794 0.9906)
			(end -0.2794 0.9906)
			(stroke
				(width 0.1)
				(type default)
			)
			(layer "B.Fab")
		)
		(fp_line
			(start 0.2794 -0.1016)
			(end 0.2794 0.9906)
			(stroke
				(width 0.1)
				(type default)
			)
			(layer "B.Fab")
		)
		(fp_line
			(start -0.2794 0.9906)
			(end -0.2794 -0.1016)
			(stroke
				(width 0.1)
				(type default)
			)
			(layer "B.Fab")
		)
		(fp_line
			(start -0.2794 -0.1016)
			(end 0.2794 -0.1016)
			(stroke
				(width 0.1)
				(type default)
			)
			(layer "B.Fab")
		)
		(pad "1" smd rect
			(at 0 0)
			(size 0.508 0.508)
			(layers "B.Cu" "B.Mask" "B.Paste")
			(net "P3V3_STBY")
		)
		(pad "2" smd rect
			(at 0 0.889)
			(size 0.508 0.508)
			(layers "B.Cu" "B.Mask" "B.Paste")
			(net "FM_POST_CARD_PRES_BMC_R1_N")
		)
		(zone
			(layer "B.Cu")
			(hatch none 0.5)
			(connect_pads
				(clearance 0)
			)
			(min_thickness 0.25)
			(keepout
				(tracks not_allowed)
				(vias allowed)
				(pads allowed)
				(copperpour not_allowed)
				(footprints allowed)
			)
			(placement
				(enabled no)
				(sheetname "")
			)
			(fill
				(thermal_gap 0.5)
				(thermal_bridge_width 0.5)
				(island_removal_mode 0)
			)
			(polygon
				(pts
					(xy 399.637758 -116.952014) (xy 400.145758 -116.952014) (xy 400.145758 -116.571014) (xy 399.637758 -116.571014)
				)
			)
		)
		(zone
			(layer "B.Cu")
			(hatch none 0.5)
			(connect_pads
				(clearance 0)
			)
			(min_thickness 0.25)
			(keepout
				(tracks allowed)
				(vias not_allowed)
				(pads allowed)
				(copperpour not_allowed)
				(footprints allowed)
			)
			(placement
				(enabled no)
				(sheetname "")
			)
			(fill
				(thermal_gap 0.5)
				(thermal_bridge_width 0.5)
				(island_removal_mode 0)
			)
			(polygon
				(pts
					(xy 399.637758 -116.571014) (xy 400.145758 -116.571014) (xy 400.145758 -116.952014) (xy 399.637758 -116.952014)
				)
			)
		)
	)
	(footprint ""
		(layer "B.Cu")
		(at 404.43658 -141.783816 -90)
		(property "Reference" "C2L45"
			(at 0 0 90)
			(layer "B.SilkS")
			(hide yes)
			(effects
				(font
					(size 1.27 1.27)
				)
				(justify mirror)
			)
		)
		(property "Value" ""
			(at 0 0 90)
			(layer "B.Fab")
			(effects
				(font
					(size 1.27 1.27)
				)
				(justify mirror)
			)
		)
		(duplicate_pad_numbers_are_jumpers no)
		(fp_poly
			(pts
				(xy 0.7239 -0.2159) (xy -0.7239 -0.2159) (xy -0.7239 1.9939) (xy 0.7239 1.9939)
			)
			(stroke
				(width 0)
				(type default)
			)
			(fill no)
			(layer "B.CrtYd")
		)
		(fp_line
			(start -0.7239 1.9939)
			(end -0.7239 -0.2159)
			(stroke
				(width 0.1)
				(type default)
			)
			(layer "B.Fab")
		)
		(fp_line
			(start 0.7239 1.9939)
			(end -0.7239 1.9939)
			(stroke
				(width 0.1)
				(type default)
			)
			(layer "B.Fab")
		)
		(fp_line
			(start -0.7239 -0.2159)
			(end 0.7239 -0.2159)
			(stroke
				(width 0.1)
				(type default)
			)
			(layer "B.Fab")
		)
		(fp_line
			(start 0.7239 -0.2159)
			(end 0.7239 1.9939)
			(stroke
				(width 0.1)
				(type default)
			)
			(layer "B.Fab")
		)
		(pad "1" smd rect
			(at 0 0 90)
			(size 1.27 1.016)
			(layers "B.Cu" "B.Mask" "B.Paste")
			(net "P1V8_PCH_STBY")
		)
		(pad "2" smd rect
			(at 0 1.778 90)
			(size 1.27 1.016)
			(layers "B.Cu" "B.Mask" "B.Paste")
			(net "GND")
		)
		(zone
			(layer "B.Cu")
			(hatch none 0.5)
			(connect_pads
				(clearance 0)
			)
			(min_thickness 0.25)
			(keepout
				(tracks not_allowed)
				(vias allowed)
				(pads allowed)
				(copperpour not_allowed)
				(footprints allowed)
			)
			(placement
				(enabled no)
				(sheetname "")
			)
			(fill
				(thermal_gap 0.5)
				(thermal_bridge_width 0.5)
				(island_removal_mode 0)
			)
			(polygon
				(pts
					(xy 403.92858 -141.148816) (xy 403.92858 -142.418816) (xy 403.16658 -142.418816) (xy 403.16658 -141.148816)
				)
			)
		)
	)
	(footprint ""
		(layer "B.Cu")
		(at 401.32 -102.8319)
		(property "Reference" "C2N14"
			(at 0 0 0)
			(layer "B.SilkS")
			(hide yes)
			(effects
				(font
					(size 1.27 1.27)
				)
				(justify mirror)
			)
		)
		(property "Value" ""
			(at 0 0 0)
			(layer "B.Fab")
			(effects
				(font
					(size 1.27 1.27)
				)
				(justify mirror)
			)
		)
		(duplicate_pad_numbers_are_jumpers no)
		(fp_poly
			(pts
				(xy 0.4953 -0.2032) (xy -0.4953 -0.2032) (xy -0.4953 1.6002) (xy 0.4953 1.6002)
			)
			(stroke
				(width 0)
				(type default)
			)
			(fill no)
			(layer "B.CrtYd")
		)
		(fp_line
			(start -0.4953 -0.2032)
			(end -0.4953 1.6002)
			(stroke
				(width 0.1)
				(type default)
			)
			(layer "B.Fab")
		)
		(fp_line
			(start -0.4953 1.6002)
			(end 0.4953 1.6002)
			(stroke
				(width 0.1)
				(type default)
			)
			(layer "B.Fab")
		)
		(fp_line
			(start 0.4953 -0.2032)
			(end -0.4953 -0.2032)
			(stroke
				(width 0.1)
				(type default)
			)
			(layer "B.Fab")
		)
		(fp_line
			(start 0.4953 1.6002)
			(end 0.4953 -0.2032)
			(stroke
				(width 0.1)
				(type default)
			)
			(layer "B.Fab")
		)
		(pad "1" smd rect
			(at 0 0 180)
			(size 0.762 0.889)
			(layers "B.Cu" "B.Mask" "B.Paste")
			(net "P3V3_STBY")
		)
		(pad "2" smd rect
			(at 0 1.397 180)
			(size 0.762 0.889)
			(layers "B.Cu" "B.Mask" "B.Paste")
			(net "GND")
		)
		(zone
			(layer "B.Cu")
			(hatch none 0.5)
			(connect_pads
				(clearance 0)
			)
			(min_thickness 0.25)
			(keepout
				(tracks not_allowed)
				(vias allowed)
				(pads allowed)
				(copperpour not_allowed)
				(footprints allowed)
			)
			(placement
				(enabled no)
				(sheetname "")
			)
			(fill
				(thermal_gap 0.5)
				(thermal_bridge_width 0.5)
				(island_removal_mode 0)
			)
			(polygon
				(pts
					(xy 401.701 -102.3874) (xy 400.939 -102.3874) (xy 400.939 -101.8794) (xy 401.701 -101.8794)
				)
			)
		)
	)
	(footprint ""
		(layer "B.Cu")
		(at 338.934806 -61.257434)
		(property "Reference" "C2U7"
			(at 0 0 0)
			(layer "B.SilkS")
			(hide yes)
			(effects
				(font
					(size 1.27 1.27)
				)
				(justify mirror)
			)
		)
		(property "Value" ""
			(at 0 0 0)
			(layer "B.Fab")
			(effects
				(font
					(size 1.27 1.27)
				)
				(justify mirror)
			)
		)
		(duplicate_pad_numbers_are_jumpers no)
		(fp_poly
			(pts
				(xy -0.3048 -0.1016) (xy -0.3048 0.9906) (xy 0.3048 0.9906) (xy 0.3048 -0.1016)
			)
			(stroke
				(width 0)
				(type default)
			)
			(fill no)
			(layer "B.CrtYd")
		)
		(fp_line
			(start -0.3048 -0.1016)
			(end 0.3048 -0.1016)
			(stroke
				(width 0.1)
				(type default)
			)
			(layer "B.Fab")
		)
		(fp_line
			(start -0.3048 0.9906)
			(end -0.3048 -0.1016)
			(stroke
				(width 0.1)
				(type default)
			)
			(layer "B.Fab")
		)
		(fp_line
			(start 0.3048 -0.1016)
			(end 0.3048 0.9906)
			(stroke
				(width 0.1)
				(type default)
			)
			(layer "B.Fab")
		)
		(fp_line
			(start 0.3048 0.9906)
			(end -0.3048 0.9906)
			(stroke
				(width 0.1)
				(type default)
			)
			(layer "B.Fab")
		)
		(pad "1" smd rect
			(at 0 0 180)
			(size 0.508 0.508)
			(layers "B.Cu" "B.Mask" "B.Paste")
			(net "P3E_CPU0_PE1_PCH_RXP<2>")
		)
		(pad "2" smd rect
			(at 0 0.889 180)
			(size 0.508 0.508)
			(layers "B.Cu" "B.Mask" "B.Paste")
			(net "P3E_CPU0_PE1_SS_RXP<2>")
		)
		(zone
			(layer "B.Cu")
			(hatch none 0.5)
			(connect_pads
				(clearance 0)
			)
			(min_thickness 0.25)
			(keepout
				(tracks allowed)
				(vias not_allowed)
				(pads allowed)
				(copperpour not_allowed)
				(footprints allowed)
			)
			(placement
				(enabled no)
				(sheetname "")
			)
			(fill
				(thermal_gap 0.5)
				(thermal_bridge_width 0.5)
				(island_removal_mode 0)
			)
			(polygon
				(pts
					(xy 339.188806 -61.003434) (xy 338.680806 -61.003434) (xy 338.680806 -60.622434) (xy 339.188806 -60.622434)
				)
			)
		)
		(zone
			(layer "B.Cu")
			(hatch none 0.5)
			(connect_pads
				(clearance 0)
			)
			(min_thickness 0.25)
			(keepout
				(tracks not_allowed)
				(vias allowed)
				(pads allowed)
				(copperpour not_allowed)
				(footprints allowed)
			)
			(placement
				(enabled no)
				(sheetname "")
			)
			(fill
				(thermal_gap 0.5)
				(thermal_bridge_width 0.5)
				(island_removal_mode 0)
			)
			(polygon
				(pts
					(xy 339.188806 -60.622434) (xy 338.680806 -60.622434) (xy 338.680806 -61.003434) (xy 339.188806 -61.003434)
				)
			)
		)
	)
)
